# T6G (Grand Teton) — schematic netlist excerpt (pin names and nets, part order shuffled) for the footprints in the layout excerpt that follows; sources: Cadence DE-HDL packaged netlist, KiCad conversion of 04192023_DAF0TMB3IC0_F0TG_MB_C_brd_V02_OCP.brd

PR255  Q_RES  8.87K 1% EMPTY  pkg 0402LF  page 218 : A = PVDDCR_CPU1_P1_LSET1 ; B = GND
C733  Q_CAP_DIFFBUS  DIFF BUS_0.22UF 6.3V 20% X6S  pkg C0201  page 66 : \1\ = P5E_CPU1_P1_TX_C_DP<4> ; \2\ = P5E_CPU1_P1_TX_DP<4>
PC2190  Q_CAP  0.01UF 50V 10% X7R  pkg C0402  page 262 : A = HSC_VOSEN ; B = AGND_HSC

(kicad_pcb
	(version 20260206)
	(generator "pcbnew")
	(generator_version "10.0")
	(general
		(thickness 1.6)
		(legacy_teardrops no)
	)
	(paper "A4")
	(title_block
		(title "04192023_DAF0TMB3IC0_F0TG_MB_C_brd_V02_OCP.brd")
		(comment 1 "Grand Teton / footprints 193-195 of 8354")
	)
	(layers
		(0 "F.Cu" signal "TOP")
		(4 "In1.Cu" signal "GND")
		(6 "In2.Cu" signal "IN1")
		(8 "In3.Cu" signal "GND1")
		(10 "In4.Cu" signal "IN2")
		(12 "In5.Cu" signal "GND2")
		(14 "In6.Cu" signal "IN3")
		(16 "In7.Cu" signal "GND3")
		(18 "In8.Cu" signal "VCC")
		(20 "In9.Cu" signal "VCC1")
		(22 "In10.Cu" signal "GND4")
		(24 "In11.Cu" signal "IN4")
		(26 "In12.Cu" signal "GND5")
		(28 "In13.Cu" signal "IN5")
		(30 "In14.Cu" signal "GND6")
		(32 "In15.Cu" signal "IN6")
		(34 "In16.Cu" signal "GND7")
		(2 "B.Cu" signal "BOTTOM")
		(9 "F.Adhes" user "F.Adhesive")
		(11 "B.Adhes" user "B.Adhesive")
		(13 "F.Paste" user "Package Geometry/Pastemask Top")
		(15 "B.Paste" user "Package Geometry/Pastemask Bottom")
		(5 "F.SilkS" user "Ref Des/Silkscreen Top")
		(7 "B.SilkS" user "Ref Des/Silkscreen Bottom")
		(1 "F.Mask" user "Board Geometry/Soldermask Top")
		(3 "B.Mask" user "Board Geometry/Soldermask Bottom")
		(17 "Dwgs.User" user "User.Drawings")
		(19 "Cmts.User" user "User.Comments")
		(21 "Eco1.User" user "User.Eco1")
		(23 "Eco2.User" user "User.Eco2")
		(25 "Edge.Cuts" user "Board Geometry/Outline")
		(27 "Margin" user)
		(31 "F.CrtYd" user "Package Geometry/Place Bound Top")
		(29 "B.CrtYd" user "Package Geometry/Place Bound Bottom")
		(35 "F.Fab" user "Ref Des/Assembly Top")
		(33 "B.Fab" user "Ref Des/Assembly Bottom")
	)
	(footprint ""
		(layer "F.Cu")
		(at 85.81771 -340.190074)
		(property "Reference" "PR255"
			(at 0 0 0)
			(layer "F.SilkS")
			(hide yes)
			(effects
				(font
					(size 1.27 1.27)
				)
			)
		)
		(property "Value" ""
			(at 0 0 0)
			(layer "F.Fab")
			(effects
				(font
					(size 1.27 1.27)
				)
			)
		)
		(duplicate_pad_numbers_are_jumpers no)
		(fp_line
			(start -0.7874 -0.4064)
			(end 0.7874 -0.4064)
			(stroke
				(width 0.1524)
				(type default)
			)
			(layer "F.SilkS")
		)
		(fp_line
			(start -0.7874 0.4064)
			(end -0.7874 -0.4064)
			(stroke
				(width 0.1524)
				(type default)
			)
			(layer "F.SilkS")
		)
		(fp_line
			(start 0.7874 -0.4064)
			(end 0.7874 0.4064)
			(stroke
				(width 0.1524)
				(type default)
			)
			(layer "F.SilkS")
		)
		(fp_line
			(start 0.7874 0.4064)
			(end -0.7874 0.4064)
			(stroke
				(width 0.1524)
				(type default)
			)
			(layer "F.SilkS")
		)
		(fp_line
			(start -0.67945 -0.305054)
			(end -0.12065 -0.305054)
			(stroke
				(width 0.1)
				(type default)
			)
			(layer "F.Fab")
		)
		(fp_line
			(start -0.67945 0.3048)
			(end -0.67945 -0.305054)
			(stroke
				(width 0.1)
				(type default)
			)
			(layer "F.Fab")
		)
		(fp_line
			(start -0.12065 -0.305054)
			(end -0.12065 -0.2794)
			(stroke
				(width 0.1)
				(type default)
			)
			(layer "F.Fab")
		)
		(fp_line
			(start -0.12065 -0.2794)
			(end 0.12065 -0.2794)
			(stroke
				(width 0.1)
				(type default)
			)
			(layer "F.Fab")
		)
		(fp_line
			(start -0.12065 0.2794)
			(end -0.12065 0.3048)
			(stroke
				(width 0.1)
				(type default)
			)
			(layer "F.Fab")
		)
		(fp_line
			(start -0.12065 0.3048)
			(end -0.67945 0.3048)
			(stroke
				(width 0.1)
				(type default)
			)
			(layer "F.Fab")
		)
		(fp_line
			(start 0.120396 0.2794)
			(end -0.12065 0.2794)
			(stroke
				(width 0.1)
				(type default)
			)
			(layer "F.Fab")
		)
		(fp_line
			(start 0.120396 0.3048)
			(end 0.120396 0.2794)
			(stroke
				(width 0.1)
				(type default)
			)
			(layer "F.Fab")
		)
		(fp_line
			(start 0.12065 -0.3048)
			(end 0.67945 -0.3048)
			(stroke
				(width 0.1)
				(type default)
			)
			(layer "F.Fab")
		)
		(fp_line
			(start 0.12065 -0.2794)
			(end 0.12065 -0.3048)
			(stroke
				(width 0.1)
				(type default)
			)
			(layer "F.Fab")
		)
		(fp_line
			(start 0.67945 -0.3048)
			(end 0.67945 0.3048)
			(stroke
				(width 0.1)
				(type default)
			)
			(layer "F.Fab")
		)
		(fp_line
			(start 0.67945 0.3048)
			(end 0.120396 0.3048)
			(stroke
				(width 0.1)
				(type default)
			)
			(layer "F.Fab")
		)
		(pad "1" smd circle
			(at -0.40005 0)
			(size 0 0)
			(layers "F.Cu" "F.Mask" "F.Paste")
			(net "PVDDCR_CPU1_P1_LSET1")
		)
		(pad "2" smd circle
			(at 0.40005 0)
			(size 0 0)
			(layers "F.Cu" "F.Mask" "F.Paste")
			(net "GND")
		)
	)
	(footprint ""
		(layer "F.Cu")
		(at 182.5625 -397.848582 180)
		(property "Reference" "PC2190"
			(at 0 0 180)
			(layer "F.SilkS")
			(hide yes)
			(effects
				(font
					(size 1.27 1.27)
				)
			)
		)
		(property "Value" ""
			(at 0 0 180)
			(layer "F.Fab")
			(effects
				(font
					(size 1.27 1.27)
				)
			)
		)
		(duplicate_pad_numbers_are_jumpers no)
		(fp_line
			(start 0.7874 0.4064)
			(end -0.7874 0.4064)
			(stroke
				(width 0.1524)
				(type default)
			)
			(layer "F.SilkS")
		)
		(fp_line
			(start 0.7874 -0.4064)
			(end 0.7874 0.4064)
			(stroke
				(width 0.1524)
				(type default)
			)
			(layer "F.SilkS")
		)
		(fp_line
			(start -0.7874 0.4064)
			(end -0.7874 -0.4064)
			(stroke
				(width 0.1524)
				(type default)
			)
			(layer "F.SilkS")
		)
		(fp_line
			(start -0.7874 -0.4064)
			(end 0.7874 -0.4064)
			(stroke
				(width 0.1524)
				(type default)
			)
			(layer "F.SilkS")
		)
		(fp_line
			(start 0.67945 0.3048)
			(end 0.120396 0.3048)
			(stroke
				(width 0.1)
				(type default)
			)
			(layer "F.Fab")
		)
		(fp_line
			(start 0.67945 -0.3048)
			(end 0.67945 0.3048)
			(stroke
				(width 0.1)
				(type default)
			)
			(layer "F.Fab")
		)
		(fp_line
			(start 0.12065 -0.2794)
			(end 0.12065 -0.3048)
			(stroke
				(width 0.1)
				(type default)
			)
			(layer "F.Fab")
		)
		(fp_line
			(start 0.12065 -0.3048)
			(end 0.67945 -0.3048)
			(stroke
				(width 0.1)
				(type default)
			)
			(layer "F.Fab")
		)
		(fp_line
			(start 0.120396 0.3048)
			(end 0.120396 0.2794)
			(stroke
				(width 0.1)
				(type default)
			)
			(layer "F.Fab")
		)
		(fp_line
			(start 0.120396 0.2794)
			(end -0.12065 0.2794)
			(stroke
				(width 0.1)
				(type default)
			)
			(layer "F.Fab")
		)
		(fp_line
			(start -0.12065 0.3048)
			(end -0.67945 0.3048)
			(stroke
				(width 0.1)
				(type default)
			)
			(layer "F.Fab")
		)
		(fp_line
			(start -0.12065 0.2794)
			(end -0.12065 0.3048)
			(stroke
				(width 0.1)
				(type default)
			)
			(layer "F.Fab")
		)
		(fp_line
			(start -0.12065 -0.2794)
			(end 0.12065 -0.2794)
			(stroke
				(width 0.1)
				(type default)
			)
			(layer "F.Fab")
		)
		(fp_line
			(start -0.12065 -0.305054)
			(end -0.12065 -0.2794)
			(stroke
				(width 0.1)
				(type default)
			)
			(layer "F.Fab")
		)
		(fp_line
			(start -0.67945 0.3048)
			(end -0.67945 -0.305054)
			(stroke
				(width 0.1)
				(type default)
			)
			(layer "F.Fab")
		)
		(fp_line
			(start -0.67945 -0.305054)
			(end -0.12065 -0.305054)
			(stroke
				(width 0.1)
				(type default)
			)
			(layer "F.Fab")
		)
		(pad "1" smd circle
			(at -0.40005 0 180)
			(size 0 0)
			(layers "F.Cu" "F.Mask" "F.Paste")
			(net "HSC_VOSEN")
		)
		(pad "2" smd circle
			(at 0.40005 0 180)
			(size 0 0)
			(layers "F.Cu" "F.Mask" "F.Paste")
			(net "AGND_HSC")
		)
	)
	(footprint ""
		(layer "F.Cu")
		(at 80.622902 -375.49963 -90)
		(property "Reference" "C733"
			(at 0 0 270)
			(layer "F.SilkS")
			(hide yes)
			(effects
				(font
					(size 1.27 1.27)
				)
			)
		)
		(property "Value" ""
			(at 0 0 270)
			(layer "F.Fab")
			(effects
				(font
					(size 1.27 1.27)
				)
			)
		)
		(duplicate_pad_numbers_are_jumpers no)
		(fp_line
			(start -0.299974 0.150114)
			(end -0.299974 -0.150114)
			(stroke
				(width 0.1)
				(type default)
			)
			(layer "F.Fab")
		)
		(fp_line
			(start 0.299974 0.150114)
			(end -0.299974 0.150114)
			(stroke
				(width 0.1)
				(type default)
			)
			(layer "F.Fab")
		)
		(fp_line
			(start -0.299974 -0.150114)
			(end 0.299974 -0.150114)
			(stroke
				(width 0.1)
				(type default)
			)
			(layer "F.Fab")
		)
		(fp_line
			(start 0.299974 -0.150114)
			(end 0.299974 0.150114)
			(stroke
				(width 0.1)
				(type default)
			)
			(layer "F.Fab")
		)
		(pad "1" smd rect
			(at -0.2667 0 270)
			(size 0.3048 0.381)
			(layers "F.Cu" "F.Mask" "F.Paste")
			(net "P5E_CPU1_P1_TX_C_DP<4>")
		)
		(pad "2" smd rect
			(at 0.2667 0 270)
			(size 0.3048 0.381)
			(layers "F.Cu" "F.Mask" "F.Paste")
			(net "P5E_CPU1_P1_TX_DP<4>")
		)
	)
)
